# TIMECARD (Time Appliance Project (Time Card)) — schematic netlist excerpt (pin names and nets, part order shuffled) for the footprints in the layout excerpt that follows; sources: Cadence DE-HDL packaged netlist, KiCad conversion of R4006-B0001-02_R01.brd

C141  CAPACITOR  0.1UF 10V 10%  pkg SMC_0402R_H022  page 14 : \1\ = XP1R0V_FPGA_VCCINT ; \2\ = SG

(kicad_pcb
	(version 20260206)
	(generator "pcbnew")
	(generator_version "10.0")
	(general
		(thickness 1.6)
		(legacy_teardrops no)
	)
	(paper "A4")
	(title_block
		(title "timecard-production-celestica-r4006 — R4006-B0001-02_R01.brd")
		(comment 1 "Time Appliance Project (Time Card) / footprints 712-712 of 1113")
	)
	(layers
		(0 "F.Cu" signal "TOP")
		(4 "In1.Cu" signal "L02_GND1")
		(6 "In2.Cu" signal "L03_SIG1")
		(8 "In3.Cu" signal "L04_GND2")
		(10 "In4.Cu" signal "L05_VCC1")
		(12 "In5.Cu" signal "L06_VCC2")
		(14 "In6.Cu" signal "L07_GND3")
		(16 "In7.Cu" signal "L08_SIG2")
		(18 "In8.Cu" signal "L09_GND4")
		(2 "B.Cu" signal "BOTTOM")
		(9 "F.Adhes" user "F.Adhesive")
		(11 "B.Adhes" user "B.Adhesive")
		(13 "F.Paste" user "Package Geometry/Pastemask Top")
		(15 "B.Paste" user "Package Geometry/Pastemask Bottom")
		(5 "F.SilkS" user "Ref Des/Silkscreen Top")
		(7 "B.SilkS" user "Ref Des/Silkscreen Bottom")
		(1 "F.Mask" user "Board Geometry/Soldermask Top")
		(3 "B.Mask" user "Board Geometry/Soldermask Bottom")
		(17 "Dwgs.User" user "User.Drawings")
		(19 "Cmts.User" user "User.Comments")
		(21 "Eco1.User" user "User.Eco1")
		(23 "Eco2.User" user "User.Eco2")
		(25 "Edge.Cuts" user "Board Geometry/Outline")
		(27 "Margin" user)
		(31 "F.CrtYd" user "Package Geometry/Place Bound Top")
		(29 "B.CrtYd" user "Package Geometry/Place Bound Bottom")
		(35 "F.Fab" user "Ref Des/Assembly Top")
		(33 "B.Fab" user "Ref Des/Assembly Bottom")
	)
	(footprint ""
		(layer "B.Cu")
		(at 107.347258 -39.823136 180)
		(property "Reference" "C141"
			(at 41.274238 -1.251966 0)
			(unlocked yes)
			(layer "B.SilkS")
			(effects
				(font
					(size 0.635 0.4064)
					(thickness 0.1524)
				)
				(justify mirror)
			)
		)
		(property "Value" "VAL*"
			(at 0 3.718306 180)
			(unlocked yes)
			(layer "B.Fab")
			(hide yes)
			(effects
				(font
					(size 0.7874 0.5842)
					(thickness 0.127)
				)
				(justify mirror)
			)
		)
		(property "Device Type" "CAPACITOR-G105-0B104-CK,0.1UF,A"
			(at 0 1.432306 180)
			(unlocked yes)
			(layer "B.Fab")
			(hide yes)
			(effects
				(font
					(size 0.7874 0.5842)
					(thickness 0.127)
				)
				(justify mirror)
			)
		)
		(property "User Part Number" "PARTNUM*"
			(at 0 2.575306 180)
			(unlocked yes)
			(layer "Cmts.User")
			(hide yes)
			(effects
				(font
					(size 0.7874 0.5842)
					(thickness 0.127)
				)
				(justify mirror)
			)
		)
		(property "Tolerance" "TOL*"
			(at 0 4.861306 180)
			(unlocked yes)
			(layer "Cmts.User")
			(hide yes)
			(effects
				(font
					(size 0.7874 0.5842)
					(thickness 0.127)
				)
				(justify mirror)
			)
		)
		(duplicate_pad_numbers_are_jumpers no)
		(fp_line
			(start 0.970026 0.4699)
			(end 0.970026 -0.4699)
			(stroke
				(width 0.1)
				(type default)
			)
			(layer "B.SilkS")
		)
		(fp_line
			(start 0.970026 -0.4699)
			(end -0.970026 -0.4699)
			(stroke
				(width 0.1)
				(type default)
			)
			(layer "B.SilkS")
		)
		(fp_line
			(start -0.970026 0.4699)
			(end 0.970026 0.4699)
			(stroke
				(width 0.1)
				(type default)
			)
			(layer "B.SilkS")
		)
		(fp_line
			(start -0.970026 -0.4699)
			(end -0.970026 0.4699)
			(stroke
				(width 0.1)
				(type default)
			)
			(layer "B.SilkS")
		)
		(fp_poly
			(pts
				(xy 0.970026 0.4699) (xy -0.970026 0.4699) (xy -0.970026 -0.4699) (xy 0.970026 -0.4699)
			)
			(stroke
				(width 0)
				(type default)
			)
			(fill no)
			(layer "B.CrtYd")
		)
		(fp_line
			(start 0.508 0.3048)
			(end 0.508 -0.3048)
			(stroke
				(width 0.1)
				(type default)
			)
			(layer "B.Fab")
		)
		(fp_line
			(start 0.508 -0.3048)
			(end -0.508 -0.3048)
			(stroke
				(width 0.1)
				(type default)
			)
			(layer "B.Fab")
		)
		(fp_line
			(start -0.508 0.3048)
			(end 0.508 0.3048)
			(stroke
				(width 0.1)
				(type default)
			)
			(layer "B.Fab")
		)
		(fp_line
			(start -0.508 -0.3048)
			(end -0.508 0.3048)
			(stroke
				(width 0.1)
				(type default)
			)
			(layer "B.Fab")
		)
		(pad "1" smd circle
			(at 0.500126 0)
			(size 0.635 0.635)
			(layers "B.Cu" "B.Mask" "B.Paste")
			(net "XP1R0V_FPGA_VCCINT")
		)
		(pad "2" smd circle
			(at -0.500126 0)
			(size 0.635 0.635)
			(layers "B.Cu" "B.Mask" "B.Paste")
			(net "SG")
		)
	)
)
